(kicad_pcb
	(version 20260206)
	(generator "pcbnew")
	(generator_version "10.0")
	(general
		(thickness 1.6)
		(legacy_teardrops no)
	)
	(paper "A4")
	(title_block
		(title "04192023_DAF0TMB3IC0_F0TG_MB_C_brd_V02_OCP.brd")
		(comment 1 "Grand Teton / footprints 5144-5151 of 8354")
	)
	(layers
		(0 "F.Cu" signal "TOP")
		(4 "In1.Cu" signal "GND")
		(6 "In2.Cu" signal "IN1")
		(8 "In3.Cu" signal "GND1")
		(10 "In4.Cu" signal "IN2")
		(12 "In5.Cu" signal "GND2")
		(14 "In6.Cu" signal "IN3")
		(16 "In7.Cu" signal "GND3")
		(18 "In8.Cu" signal "VCC")
		(20 "In9.Cu" signal "VCC1")
		(22 "In10.Cu" signal "GND4")
		(24 "In11.Cu" signal "IN4")
		(26 "In12.Cu" signal "GND5")
		(28 "In13.Cu" signal "IN5")
		(30 "In14.Cu" signal "GND6")
		(32 "In15.Cu" signal "IN6")
		(34 "In16.Cu" signal "GND7")
		(2 "B.Cu" signal "BOTTOM")
		(9 "F.Adhes" user "F.Adhesive")
		(11 "B.Adhes" user "B.Adhesive")
		(13 "F.Paste" user "Package Geometry/Pastemask Top")
		(15 "B.Paste" user "Package Geometry/Pastemask Bottom")
		(5 "F.SilkS" user "Ref Des/Silkscreen Top")
		(7 "B.SilkS" user "Ref Des/Silkscreen Bottom")
		(1 "F.Mask" user "Board Geometry/Soldermask Top")
		(3 "B.Mask" user "Board Geometry/Soldermask Bottom")
		(17 "Dwgs.User" user "User.Drawings")
		(19 "Cmts.User" user "User.Comments")
		(21 "Eco1.User" user "User.Eco1")
		(23 "Eco2.User" user "User.Eco2")
		(25 "Edge.Cuts" user "Board Geometry/Outline")
		(27 "Margin" user)
		(31 "F.CrtYd" user "Package Geometry/Place Bound Top")
		(29 "B.CrtYd" user "Package Geometry/Place Bound Bottom")
		(35 "F.Fab" user "Ref Des/Assembly Top")
		(33 "B.Fab" user "Ref Des/Assembly Bottom")
	)
	(footprint ""
		(layer "B.Cu")
		(at 182.308246 -421.375586 90)
		(property "Reference" "R6235"
			(at 0 0 90)
			(layer "B.SilkS")
			(hide yes)
			(effects
				(font
					(size 1.27 1.27)
				)
				(justify mirror)
			)
		)
		(property "Value" ""
			(at 0 0 90)
			(layer "B.Fab")
			(effects
				(font
					(size 1.27 1.27)
				)
				(justify mirror)
			)
		)
		(duplicate_pad_numbers_are_jumpers no)
		(fp_line
			(start 0.7874 -0.4064)
			(end -0.7874 -0.4064)
			(stroke
				(width 0.1524)
				(type default)
			)
			(layer "B.SilkS")
		)
		(fp_line
			(start -0.7874 -0.4064)
			(end -0.7874 0.4064)
			(stroke
				(width 0.1524)
				(type default)
			)
			(layer "B.SilkS")
		)
		(fp_line
			(start 0.7874 0.4064)
			(end 0.7874 -0.4064)
			(stroke
				(width 0.1524)
				(type default)
			)
			(layer "B.SilkS")
		)
		(fp_line
			(start -0.7874 0.4064)
			(end 0.7874 0.4064)
			(stroke
				(width 0.1524)
				(type default)
			)
			(layer "B.SilkS")
		)
		(fp_line
			(start 0.67945 -0.305054)
			(end 0.12065 -0.305054)
			(stroke
				(width 0.1)
				(type default)
			)
			(layer "B.Fab")
		)
		(fp_line
			(start 0.12065 -0.305054)
			(end 0.12065 -0.2794)
			(stroke
				(width 0.1)
				(type default)
			)
			(layer "B.Fab")
		)
		(fp_line
			(start -0.12065 -0.3048)
			(end -0.67945 -0.3048)
			(stroke
				(width 0.1)
				(type default)
			)
			(layer "B.Fab")
		)
		(fp_line
			(start -0.67945 -0.3048)
			(end -0.67945 0.3048)
			(stroke
				(width 0.1)
				(type default)
			)
			(layer "B.Fab")
		)
		(fp_line
			(start 0.12065 -0.2794)
			(end -0.12065 -0.2794)
			(stroke
				(width 0.1)
				(type default)
			)
			(layer "B.Fab")
		)
		(fp_line
			(start -0.12065 -0.2794)
			(end -0.12065 -0.3048)
			(stroke
				(width 0.1)
				(type default)
			)
			(layer "B.Fab")
		)
		(fp_line
			(start 0.12065 0.2794)
			(end 0.12065 0.3048)
			(stroke
				(width 0.1)
				(type default)
			)
			(layer "B.Fab")
		)
		(fp_line
			(start -0.120396 0.2794)
			(end 0.12065 0.2794)
			(stroke
				(width 0.1)
				(type default)
			)
			(layer "B.Fab")
		)
		(fp_line
			(start 0.67945 0.3048)
			(end 0.67945 -0.305054)
			(stroke
				(width 0.1)
				(type default)
			)
			(layer "B.Fab")
		)
		(fp_line
			(start 0.12065 0.3048)
			(end 0.67945 0.3048)
			(stroke
				(width 0.1)
				(type default)
			)
			(layer "B.Fab")
		)
		(fp_line
			(start -0.120396 0.3048)
			(end -0.120396 0.2794)
			(stroke
				(width 0.1)
				(type default)
			)
			(layer "B.Fab")
		)
		(fp_line
			(start -0.67945 0.3048)
			(end -0.120396 0.3048)
			(stroke
				(width 0.1)
				(type default)
			)
			(layer "B.Fab")
		)
		(pad "1" smd circle
			(at 0.40005 0 270)
			(size 0 0)
			(layers "B.Cu" "B.Mask" "B.Paste")
			(net "A_HSC_HIGH")
		)
		(pad "2" smd circle
			(at -0.40005 0 270)
			(size 0 0)
			(layers "B.Cu" "B.Mask" "B.Paste")
			(net "GND")
		)
	)
	(footprint ""
		(layer "B.Cu")
		(at 123.01855 -388.011162 -90)
		(property "Reference" "C442"
			(at 0 0 90)
			(layer "B.SilkS")
			(hide yes)
			(effects
				(font
					(size 1.27 1.27)
				)
				(justify mirror)
			)
		)
		(property "Value" ""
			(at 0 0 90)
			(layer "B.Fab")
			(effects
				(font
					(size 1.27 1.27)
				)
				(justify mirror)
			)
		)
		(duplicate_pad_numbers_are_jumpers no)
		(fp_line
			(start -0.299974 0.150114)
			(end 0.299974 0.150114)
			(stroke
				(width 0.1)
				(type default)
			)
			(layer "B.Fab")
		)
		(fp_line
			(start 0.299974 0.150114)
			(end 0.299974 -0.150114)
			(stroke
				(width 0.1)
				(type default)
			)
			(layer "B.Fab")
		)
		(fp_line
			(start -0.299974 -0.150114)
			(end -0.299974 0.150114)
			(stroke
				(width 0.1)
				(type default)
			)
			(layer "B.Fab")
		)
		(fp_line
			(start 0.299974 -0.150114)
			(end -0.299974 -0.150114)
			(stroke
				(width 0.1)
				(type default)
			)
			(layer "B.Fab")
		)
		(pad "1" smd rect
			(at 0.2667 0 90)
			(size 0.3048 0.381)
			(layers "B.Cu" "B.Mask" "B.Paste")
			(net "P1V8_CPU1_RT3_1A")
		)
		(pad "2" smd rect
			(at -0.2667 0 90)
			(size 0.3048 0.381)
			(layers "B.Cu" "B.Mask" "B.Paste")
			(net "GND")
		)
	)
	(footprint ""
		(layer "B.Cu")
		(at 168.3004 -421.277796 -90)
		(property "Reference" "R1462"
			(at 0 0 90)
			(layer "B.SilkS")
			(hide yes)
			(effects
				(font
					(size 1.27 1.27)
				)
				(justify mirror)
			)
		)
		(property "Value" ""
			(at 0 0 90)
			(layer "B.Fab")
			(effects
				(font
					(size 1.27 1.27)
				)
				(justify mirror)
			)
		)
		(duplicate_pad_numbers_are_jumpers no)
		(fp_line
			(start -0.32512 0.175006)
			(end 0.32512 0.175006)
			(stroke
				(width 0.1)
				(type default)
			)
			(layer "B.Fab")
		)
		(fp_line
			(start 0.32512 0.175006)
			(end 0.32512 -0.175006)
			(stroke
				(width 0.1)
				(type default)
			)
			(layer "B.Fab")
		)
		(fp_line
			(start -0.32512 -0.175006)
			(end -0.32512 0.175006)
			(stroke
				(width 0.1)
				(type default)
			)
			(layer "B.Fab")
		)
		(fp_line
			(start 0.32512 -0.175006)
			(end -0.32512 -0.175006)
			(stroke
				(width 0.1)
				(type default)
			)
			(layer "B.Fab")
		)
		(pad "1" smd rect
			(at 0.2667 0 90)
			(size 0.3048 0.381)
			(layers "B.Cu" "B.Mask" "B.Paste")
			(net "P1V8_CPU1_RT_1D")
		)
		(pad "2" smd rect
			(at -0.2667 0 270)
			(size 0.3048 0.381)
			(layers "B.Cu" "B.Mask" "B.Paste")
			(net "SMB_RT_CPU1_P3_ROM_MUX_1D_SDA")
		)
	)
	(footprint ""
		(layer "B.Cu")
		(at 202.148186 -192.660016 180)
		(property "Reference" "C549"
			(at 0 0 0)
			(layer "B.SilkS")
			(hide yes)
			(effects
				(font
					(size 1.27 1.27)
				)
				(justify mirror)
			)
		)
		(property "Value" ""
			(at 0 0 0)
			(layer "B.Fab")
			(effects
				(font
					(size 1.27 1.27)
				)
				(justify mirror)
			)
		)
		(duplicate_pad_numbers_are_jumpers no)
		(fp_line
			(start 1.524 0.762)
			(end 1.524 -0.762)
			(stroke
				(width 0.1524)
				(type default)
			)
			(layer "B.SilkS")
		)
		(fp_line
			(start 1.524 -0.762)
			(end -1.524 -0.762)
			(stroke
				(width 0.1524)
				(type default)
			)
			(layer "B.SilkS")
		)
		(fp_line
			(start -1.524 0.762)
			(end 1.524 0.762)
			(stroke
				(width 0.1524)
				(type default)
			)
			(layer "B.SilkS")
		)
		(fp_line
			(start -1.524 -0.762)
			(end -1.524 0.762)
			(stroke
				(width 0.1524)
				(type default)
			)
			(layer "B.SilkS")
		)
		(fp_line
			(start 1.1049 0.724916)
			(end -1.1049 0.724916)
			(stroke
				(width 0.1)
				(type default)
			)
			(layer "B.Fab")
		)
		(fp_line
			(start 1.1049 -0.724916)
			(end 1.1049 0.724916)
			(stroke
				(width 0.1)
				(type default)
			)
			(layer "B.Fab")
		)
		(fp_line
			(start -1.1049 0.724916)
			(end -1.1049 -0.724916)
			(stroke
				(width 0.1)
				(type default)
			)
			(layer "B.Fab")
		)
		(fp_line
			(start -1.1049 -0.724916)
			(end 1.1049 -0.724916)
			(stroke
				(width 0.1)
				(type default)
			)
			(layer "B.Fab")
		)
		(pad "1" smd rect
			(at 0.889 0 180)
			(size 1.016 1.27)
			(layers "B.Cu" "B.Mask" "B.Paste")
			(net "P12V_MEM_CPU1")
		)
		(pad "2" smd rect
			(at -0.889 0 180)
			(size 1.016 1.27)
			(layers "B.Cu" "B.Mask" "B.Paste")
			(net "GND")
		)
	)
	(footprint ""
		(layer "B.Cu")
		(at 371.646958 -245.868952 -90)
		(property "Reference" "C2198"
			(at 0 0 90)
			(layer "B.SilkS")
			(hide yes)
			(effects
				(font
					(size 1.27 1.27)
				)
				(justify mirror)
			)
		)
		(property "Value" ""
			(at 0 0 90)
			(layer "B.Fab")
			(effects
				(font
					(size 1.27 1.27)
				)
				(justify mirror)
			)
		)
		(duplicate_pad_numbers_are_jumpers no)
		(fp_line
			(start -0.7874 0.4064)
			(end 0.7874 0.4064)
			(stroke
				(width 0.1524)
				(type default)
			)
			(layer "B.SilkS")
		)
		(fp_line
			(start 0.7874 0.4064)
			(end 0.7874 -0.4064)
			(stroke
				(width 0.1524)
				(type default)
			)
			(layer "B.SilkS")
		)
		(fp_line
			(start -0.7874 -0.4064)
			(end -0.7874 0.4064)
			(stroke
				(width 0.1524)
				(type default)
			)
			(layer "B.SilkS")
		)
		(fp_line
			(start 0.7874 -0.4064)
			(end -0.7874 -0.4064)
			(stroke
				(width 0.1524)
				(type default)
			)
			(layer "B.SilkS")
		)
		(fp_line
			(start -0.67945 0.3048)
			(end -0.120396 0.3048)
			(stroke
				(width 0.1)
				(type default)
			)
			(layer "B.Fab")
		)
		(fp_line
			(start -0.120396 0.3048)
			(end -0.120396 0.2794)
			(stroke
				(width 0.1)
				(type default)
			)
			(layer "B.Fab")
		)
		(fp_line
			(start 0.12065 0.3048)
			(end 0.67945 0.3048)
			(stroke
				(width 0.1)
				(type default)
			)
			(layer "B.Fab")
		)
		(fp_line
			(start 0.67945 0.3048)
			(end 0.67945 -0.305054)
			(stroke
				(width 0.1)
				(type default)
			)
			(layer "B.Fab")
		)
		(fp_line
			(start -0.120396 0.2794)
			(end 0.12065 0.2794)
			(stroke
				(width 0.1)
				(type default)
			)
			(layer "B.Fab")
		)
		(fp_line
			(start 0.12065 0.2794)
			(end 0.12065 0.3048)
			(stroke
				(width 0.1)
				(type default)
			)
			(layer "B.Fab")
		)
		(fp_line
			(start -0.12065 -0.2794)
			(end -0.12065 -0.3048)
			(stroke
				(width 0.1)
				(type default)
			)
			(layer "B.Fab")
		)
		(fp_line
			(start 0.12065 -0.2794)
			(end -0.12065 -0.2794)
			(stroke
				(width 0.1)
				(type default)
			)
			(layer "B.Fab")
		)
		(fp_line
			(start -0.67945 -0.3048)
			(end -0.67945 0.3048)
			(stroke
				(width 0.1)
				(type default)
			)
			(layer "B.Fab")
		)
		(fp_line
			(start -0.12065 -0.3048)
			(end -0.67945 -0.3048)
			(stroke
				(width 0.1)
				(type default)
			)
			(layer "B.Fab")
		)
		(fp_line
			(start 0.12065 -0.305054)
			(end 0.12065 -0.2794)
			(stroke
				(width 0.1)
				(type default)
			)
			(layer "B.Fab")
		)
		(fp_line
			(start 0.67945 -0.305054)
			(end 0.12065 -0.305054)
			(stroke
				(width 0.1)
				(type default)
			)
			(layer "B.Fab")
		)
		(pad "1" smd circle
			(at 0.40005 0 90)
			(size 0 0)
			(layers "B.Cu" "B.Mask" "B.Paste")
			(net "PVDDCR_CPU0_P0")
		)
		(pad "2" smd circle
			(at -0.40005 0 90)
			(size 0 0)
			(layers "B.Cu" "B.Mask" "B.Paste")
			(net "GND")
		)
	)
	(footprint ""
		(layer "B.Cu")
		(at 82.319114 -390.560052 90)
		(property "Reference" "C325"
			(at 0 0 90)
			(layer "B.SilkS")
			(hide yes)
			(effects
				(font
					(size 1.27 1.27)
				)
				(justify mirror)
			)
		)
		(property "Value" ""
			(at 0 0 90)
			(layer "B.Fab")
			(effects
				(font
					(size 1.27 1.27)
				)
				(justify mirror)
			)
		)
		(duplicate_pad_numbers_are_jumpers no)
		(fp_line
			(start 0.7874 -0.4064)
			(end -0.7874 -0.4064)
			(stroke
				(width 0.1524)
				(type default)
			)
			(layer "B.SilkS")
		)
		(fp_line
			(start -0.7874 -0.4064)
			(end -0.7874 0.4064)
			(stroke
				(width 0.1524)
				(type default)
			)
			(layer "B.SilkS")
		)
		(fp_line
			(start 0.7874 0.4064)
			(end 0.7874 -0.4064)
			(stroke
				(width 0.1524)
				(type default)
			)
			(layer "B.SilkS")
		)
		(fp_line
			(start -0.7874 0.4064)
			(end 0.7874 0.4064)
			(stroke
				(width 0.1524)
				(type default)
			)
			(layer "B.SilkS")
		)
		(fp_line
			(start 0.67945 -0.305054)
			(end 0.12065 -0.305054)
			(stroke
				(width 0.1)
				(type default)
			)
			(layer "B.Fab")
		)
		(fp_line
			(start 0.12065 -0.305054)
			(end 0.12065 -0.2794)
			(stroke
				(width 0.1)
				(type default)
			)
			(layer "B.Fab")
		)
		(fp_line
			(start -0.12065 -0.3048)
			(end -0.67945 -0.3048)
			(stroke
				(width 0.1)
				(type default)
			)
			(layer "B.Fab")
		)
		(fp_line
			(start -0.67945 -0.3048)
			(end -0.67945 0.3048)
			(stroke
				(width 0.1)
				(type default)
			)
			(layer "B.Fab")
		)
		(fp_line
			(start 0.12065 -0.2794)
			(end -0.12065 -0.2794)
			(stroke
				(width 0.1)
				(type default)
			)
			(layer "B.Fab")
		)
		(fp_line
			(start -0.12065 -0.2794)
			(end -0.12065 -0.3048)
			(stroke
				(width 0.1)
				(type default)
			)
			(layer "B.Fab")
		)
		(fp_line
			(start 0.12065 0.2794)
			(end 0.12065 0.3048)
			(stroke
				(width 0.1)
				(type default)
			)
			(layer "B.Fab")
		)
		(fp_line
			(start -0.120396 0.2794)
			(end 0.12065 0.2794)
			(stroke
				(width 0.1)
				(type default)
			)
			(layer "B.Fab")
		)
		(fp_line
			(start 0.67945 0.3048)
			(end 0.67945 -0.305054)
			(stroke
				(width 0.1)
				(type default)
			)
			(layer "B.Fab")
		)
		(fp_line
			(start 0.12065 0.3048)
			(end 0.67945 0.3048)
			(stroke
				(width 0.1)
				(type default)
			)
			(layer "B.Fab")
		)
		(fp_line
			(start -0.120396 0.3048)
			(end -0.120396 0.2794)
			(stroke
				(width 0.1)
				(type default)
			)
			(layer "B.Fab")
		)
		(fp_line
			(start -0.67945 0.3048)
			(end -0.120396 0.3048)
			(stroke
				(width 0.1)
				(type default)
			)
			(layer "B.Fab")
		)
		(pad "1" smd circle
			(at 0.40005 0 270)
			(size 0 0)
			(layers "B.Cu" "B.Mask" "B.Paste")
			(net "P0V9_CPU1_RT1_2A")
		)
		(pad "2" smd circle
			(at -0.40005 0 270)
			(size 0 0)
			(layers "B.Cu" "B.Mask" "B.Paste")
			(net "GND")
		)
	)
	(footprint ""
		(layer "B.Cu")
		(at 418.348922 -416.899344 90)
		(property "Reference" "C6628"
			(at 0 0 90)
			(layer "B.SilkS")
			(hide yes)
			(effects
				(font
					(size 1.27 1.27)
				)
				(justify mirror)
			)
		)
		(property "Value" ""
			(at 0 0 90)
			(layer "B.Fab")
			(effects
				(font
					(size 1.27 1.27)
				)
				(justify mirror)
			)
		)
		(duplicate_pad_numbers_are_jumpers no)
		(fp_line
			(start 0.299974 -0.150114)
			(end -0.299974 -0.150114)
			(stroke
				(width 0.1)
				(type default)
			)
			(layer "B.Fab")
		)
		(fp_line
			(start -0.299974 -0.150114)
			(end -0.299974 0.150114)
			(stroke
				(width 0.1)
				(type default)
			)
			(layer "B.Fab")
		)
		(fp_line
			(start 0.299974 0.150114)
			(end 0.299974 -0.150114)
			(stroke
				(width 0.1)
				(type default)
			)
			(layer "B.Fab")
		)
		(fp_line
			(start -0.299974 0.150114)
			(end 0.299974 0.150114)
			(stroke
				(width 0.1)
				(type default)
			)
			(layer "B.Fab")
		)
		(pad "1" smd rect
			(at 0.2667 0 270)
			(size 0.3048 0.381)
			(layers "B.Cu" "B.Mask" "B.Paste")
			(net "P5E_CPU0_P3_TX_BUF_C_DN<15>")
		)
		(pad "2" smd rect
			(at -0.2667 0 270)
			(size 0.3048 0.381)
			(layers "B.Cu" "B.Mask" "B.Paste")
			(net "P5E_CPU0_P3_TX_BUF_DN<15>")
		)
	)
	(footprint ""
		(layer "B.Cu")
		(at 98.493834 -263.521952)
		(property "Reference" "C2493"
			(at 0 0 0)
			(layer "B.SilkS")
			(hide yes)
			(effects
				(font
					(size 1.27 1.27)
				)
				(justify mirror)
			)
		)
		(property "Value" ""
			(at 0 0 0)
			(layer "B.Fab")
			(effects
				(font
					(size 1.27 1.27)
				)
				(justify mirror)
			)
		)
		(duplicate_pad_numbers_are_jumpers no)
		(fp_line
			(start -0.7874 -0.4064)
			(end -0.7874 0.4064)
			(stroke
				(width 0.1524)
				(type default)
			)
			(layer "B.SilkS")
		)
		(fp_line
			(start -0.7874 0.4064)
			(end 0.7874 0.4064)
			(stroke
				(width 0.1524)
				(type default)
			)
			(layer "B.SilkS")
		)
		(fp_line
			(start 0.7874 -0.4064)
			(end -0.7874 -0.4064)
			(stroke
				(width 0.1524)
				(type default)
			)
			(layer "B.SilkS")
		)
		(fp_line
			(start 0.7874 0.4064)
			(end 0.7874 -0.4064)
			(stroke
				(width 0.1524)
				(type default)
			)
			(layer "B.SilkS")
		)
		(fp_line
			(start -0.67945 -0.3048)
			(end -0.67945 0.3048)
			(stroke
				(width 0.1)
				(type default)
			)
			(layer "B.Fab")
		)
		(fp_line
			(start -0.67945 0.3048)
			(end -0.120396 0.3048)
			(stroke
				(width 0.1)
				(type default)
			)
			(layer "B.Fab")
		)
		(fp_line
			(start -0.12065 -0.3048)
			(end -0.67945 -0.3048)
			(stroke
				(width 0.1)
				(type default)
			)
			(layer "B.Fab")
		)
		(fp_line
			(start -0.12065 -0.2794)
			(end -0.12065 -0.3048)
			(stroke
				(width 0.1)
				(type default)
			)
			(layer "B.Fab")
		)
		(fp_line
			(start -0.120396 0.2794)
			(end 0.12065 0.2794)
			(stroke
				(width 0.1)
				(type default)
			)
			(layer "B.Fab")
		)
		(fp_line
			(start -0.120396 0.3048)
			(end -0.120396 0.2794)
			(stroke
				(width 0.1)
				(type default)
			)
			(layer "B.Fab")
		)
		(fp_line
			(start 0.12065 -0.305054)
			(end 0.12065 -0.2794)
			(stroke
				(width 0.1)
				(type default)
			)
			(layer "B.Fab")
		)
		(fp_line
			(start 0.12065 -0.2794)
			(end -0.12065 -0.2794)
			(stroke
				(width 0.1)
				(type default)
			)
			(layer "B.Fab")
		)
		(fp_line
			(start 0.12065 0.2794)
			(end 0.12065 0.3048)
			(stroke
				(width 0.1)
				(type default)
			)
			(layer "B.Fab")
		)
		(fp_line
			(start 0.12065 0.3048)
			(end 0.67945 0.3048)
			(stroke
				(width 0.1)
				(type default)
			)
			(layer "B.Fab")
		)
		(fp_line
			(start 0.67945 -0.305054)
			(end 0.12065 -0.305054)
			(stroke
				(width 0.1)
				(type default)
			)
			(layer "B.Fab")
		)
		(fp_line
			(start 0.67945 0.3048)
			(end 0.67945 -0.305054)
			(stroke
				(width 0.1)
				(type default)
			)
			(layer "B.Fab")
		)
		(pad "1" smd circle
			(at 0.40005 0 180)
			(size 0 0)
			(layers "B.Cu" "B.Mask" "B.Paste")
			(net "PVDDIO_P1")
		)
		(pad "2" smd circle
			(at -0.40005 0 180)
			(size 0 0)
			(layers "B.Cu" "B.Mask" "B.Paste")
			(net "GND")
		)
	)
)
